# BASEBOARD_FAB2 (Tioga Pass) — schematic parts with pin connectivity, parts 4650–4650 of 4751; source: Cadence DE-HDL packaged netlist (pstxprt.dat, pstxnet.dat, pstchip.dat)

U2D1  SKX_EXT_B  IC  pkg BGA1  page 55  (pins 3043-3380 of 3647)
  F63  DDR0_BG(1)  OUT  = M_G_BG<1>
  F65  RSVD(277)  BI  = TP_CPU1_RSVD_277
  F67  VSS(1138)  GROUND  = GND
  F69  VSS(1137)  GROUND  = GND
  F71  DDR1_DQ(27)  BI  = M_H_DQ<27>
  F73  DDR1_DQS_DP(3)  BI  = M_H_DQS_DP<3>
  F75  DDR1_DQ(28)  BI  = M_H_DQ<28>
  F77  DDR1_DQ(18)  BI  = M_H_DQ<18>
  F79  DDR1_DQS_DP(11)  BI  = M_H_DQS_DP<11>
  F81  DDR1_DQ(20)  BI  = M_H_DQ<20>
  F83  RSVD(276)  BI  = TP_CPU1_RSVD_276
  G2  RSVD(275)  BI  = TP_CPU1_RSVD_275
  G4  VSS(1136)  GROUND  = GND
  G6  UPI1_TX_DN(4)  OUT  = UPI_CPU1_CPU0_P1P1_DN<4>
  G8  VSS(1135)  GROUND  = GND
  G10  UPI1_TX_DN(9)  OUT  = UPI_CPU1_CPU0_P1P1_DN<9>
  G12  UPI1_TX_DP(10)  OUT  = UPI_CPU1_CPU0_P1P1_DP<10>
  G14  UPI1_TX_DN(11)  OUT  = UPI_CPU1_CPU0_P1P1_DP<11>
  G16  UPI1_TX_DP(14)  OUT  = UPI_CPU1_CPU0_P1P1_DP<14>
  G18  UPI1_TX_DN(16)  OUT  = UPI_CPU1_CPU0_P1P1_DN<16>
  G20  UPI1_TX_DP(18)  OUT  = UPI_CPU1_CPU0_P1P1_DN<18>
  G22  VSS(1134)  GROUND  = GND
  G24  VSS(1133)  GROUND  = GND
  G26  VSS(1132)  GROUND  = GND
  G28  DDR1_DQS_DN(6)  BI  = M_H_DQS_DN<6>
  G30  VSS(1131)  GROUND  = GND
  G32  VSS(1130)  GROUND  = GND
  G34  DDR1_DQS_DN(5)  BI  = M_H_DQS_DN<5>
  G36  VSS(1129)  GROUND  = GND
  G38  VSS(1128)  GROUND  = GND
  G40  DDR0_DQS_DN(4)  BI  = M_G_DQS_DN<4>
  G42  VSS(1127)  GROUND  = GND
  G46  DDR0_CID(2)  OUT  = M_G_C<2>
  G48  DDR0_ODT(3)  OUT  = M_G_ODT<3>
  G50  DDR0_ODT(2)  OUT  = M_G_ODT<2>
  G52  DDR0_CS_N(0)  OUT  = M_G_CS_N<0>
  G54  DDR0_BA(1)  OUT  = M_G_BA<1>
  G56  DDR0_CLK_DP(2)  OUT  = M_G_CLK_DP<2>
  G58  DDR0_MA(4)  OUT  = M_G_MA<4>
  G60  DDR0_MA(7)  OUT  = M_G_MA<7>
  G62  DDR0_MA(11)  OUT  = M_G_MA<11>
  G64  RSVD(274)  BI  = TP_CPU1_RSVD_274
  G66  VSS(1126)  GROUND  = GND
  G68  DDR1_DQS_DN(17)  BI  = M_H_DQS_DN<17>
  G70  VSS(1125)  GROUND  = GND
  G72  DDR1_DQ(31)  BI  = M_H_DQ<31>
  G74  DDR1_DQ(29)  BI  = M_H_DQ<29>
  G76  VSS(1124)  GROUND  = GND
  G78  VSS(1123)  GROUND  = GND
  G80  VSS(1122)  GROUND  = GND
  G82  VSS(1121)  GROUND  = GND
  G84  RSVD(273)  BI  = TP_CPU1_RSVD_273
  H1  RSVD(272)  BI  = TP_CPU1_RSVD_272
  H3  VSS(1120)  GROUND  = GND
  H5  UPI1_TX_DP(3)  OUT  = UPI_CPU1_CPU0_P1P1_DP<3>
  H7  UPI1_TX_DN(5)  OUT  = UPI_CPU1_CPU0_P1P1_DN<5>
  H9  UPI1_TX_DP(9)  OUT  = UPI_CPU1_CPU0_P1P1_DP<9>
  H11  VSS(1119)  GROUND  = GND
  H13  VCCIO(59)  POWER  = PVCCIO_CPU1
  H15  UPI1_TX_DP(13)  OUT  = UPI_CPU1_CPU0_P1P1_DP<13>
  H17  UPI1_TX_DN(14)  OUT  = UPI_CPU1_CPU0_P1P1_DN<14>
  H19  UPI1_TX_DP(17)  OUT  = UPI_CPU1_CPU0_P1P1_DP<17>
  H21  UPI1_TX_DN(19)  OUT  = UPI_CPU1_CPU0_P1P1_DP<19>
  H23  DDR0_DQ(62)  BI  = M_G_DQ<62>
  H25  VSS(1118)  GROUND  = GND
  H27  VSS(1117)  GROUND  = GND
  H29  VSS(1116)  GROUND  = GND
  H31  VSS(1115)  GROUND  = GND
  H33  VSS(1114)  GROUND  = GND
  H35  VSS(1113)  GROUND  = GND
  H37  VSS(1112)  GROUND  = GND
  H39  VSS(1111)  GROUND  = GND
  H41  VSS(1110)  GROUND  = GND
  H43  DDR1_DQ(33)  BI  = M_H_DQ<33>
  H45  VSS(153)  GROUND  = GND
  H47  VSS(190)  GROUND  = GND
  H49  VSS(219)  GROUND  = GND
  H51  VSS(233)  GROUND  = GND
  H53  VSS(304)  GROUND  = GND
  H55  VSS(352)  GROUND  = GND
  H57  VSS(379)  GROUND  = GND
  H59  VSS(399)  GROUND  = GND
  H61  VSS(407)  GROUND  = GND
  H63  VSS(428)  GROUND  = GND
  H65  VSS(1109)  GROUND  = GND
  H67  DDR1_ECC(6)  BI  = M_H_ECC<6>
  H69  DDR1_ECC(1)  BI  = M_H_ECC<1>
  H71  VSS(1108)  GROUND  = GND
  H73  DDR1_DQS_DN(3)  BI  = M_H_DQS_DN<3>
  H75  VSS(1107)  GROUND  = GND
  H77  DDR1_DQ(19)  BI  = M_H_DQ<19>
  H79  DDR1_DQS_DP(2)  BI  = M_H_DQS_DP<2>
  H81  DDR1_DQ(21)  BI  = M_H_DQ<21>
  H83  RSVD(271)  BI  = TP_CPU1_RSVD_271
  H85  RSVD(270)  BI  = TP_CPU1_RSVD_270
  J2  VCCIO(69)  POWER  = PVCCIO_CPU1
  J4  VSS(1105)  GROUND  = GND
  J6  UPI1_TX_DN(3)  OUT  = UPI_CPU1_CPU0_P1P1_DN<3>
  J8  UPI1_TX_DP(6)  OUT  = UPI_CPU1_CPU0_P1P1_DN<6>
  J10  VCCIO(58)  POWER  = PVCCIO_CPU1
  J12  VSS(1104)  GROUND  = GND
  J14  VSS(1103)  GROUND  = GND
  J16  VSS(46)  GROUND  = GND
  J18  UPI1_TX_DP(16)  OUT  = UPI_CPU1_CPU0_P1P1_DP<16>
  J20  UPI1_TX_DN(17)  OUT  = UPI_CPU1_CPU0_P1P1_DN<17>
  J22  VSS(1102)  GROUND  = GND
  J24  DDR0_DQS_DN(16)  BI  = M_G_DQS_DN<16>
  J26  VSS(1101)  GROUND  = GND
  J28  VSS(1100)  GROUND  = GND
  J30  DDR0_DQS_DN(15)  BI  = M_G_DQS_DN<15>
  J32  VSS(1099)  GROUND  = GND
  J34  VSS(1098)  GROUND  = GND
  J36  DDR0_DQS_DN(14)  BI  = M_G_DQS_DN<14>
  J38  VSS(1097)  GROUND  = GND
  J40  VSS(1096)  GROUND  = GND
  J42  DDR1_DQS_DN(13)  BI  = M_H_DQS_DN<13>
  J46  RSVD(269)  BI  = TP_CPU1_RSVD_269
  J48  DDR0_MA(13)  OUT  = M_G_MA<13>
  J50  DDR1_CS_N(4)  OUT  = M_H_CS_N<4>
  J52  DDR1_MA(0)  OUT  = M_H_MA<0>
  J54  DDR0_MA(10)  OUT  = M_G_MA<10>
  J56  DDR0_CLK_DN(2)  OUT  = M_G_CLK_DN<2>
  J58  DDR1_MA(1)  OUT  = M_H_MA<1>
  J60  DDR0_ACT_N  OUT  = M_G_ACT_N
  J62  RSVD(268)  BI  = TP_CPU1_RSVD_268
  J64  DDR0_MA(12)  OUT  = M_G_MA<12>
  J66  DDR1_ECC(2)  BI  = M_H_ECC<2>
  J68  DDR1_DQS_DP(17)  BI  = M_H_DQS_DP<17>
  J70  DDR1_ECC(0)  BI  = M_H_ECC<0>
  J72  VSS(1095)  GROUND  = GND
  J74  VSS(1094)  GROUND  = GND
  J76  VSS(1093)  GROUND  = GND
  J78  DDR1_DQ(23)  BI  = M_H_DQ<23>
  J80  DDR1_DQ(17)  BI  = M_H_DQ<17>
  J82  VSS(1092)  GROUND  = GND
  J84  VSS(1091)  GROUND  = GND
  J86  VSS(1243)  GROUND  = GND
  K1  VSS(1090)  GROUND  = GND
  K3  UPI1_TX_DP(1)  OUT  = UPI_CPU1_CPU0_P1P1_DN<1>
  K5  UPI1_TX_DN(2)  OUT  = UPI_CPU1_CPU0_P1P1_DN<2>
  K7  UPI1_TX_DP(5)  OUT  = UPI_CPU1_CPU0_P1P1_DP<5>
  K9  UPI1_TX_DN(6)  OUT  = UPI_CPU1_CPU0_P1P1_DP<6>
  K11  VSS(1089)  GROUND  = GND
  K13  VSS(1088)  GROUND  = GND
  K15  VCCIO(70)  POWER  = PVCCIO_CPU1
  K17  VSS(1087)  GROUND  = GND
  K19  UPI1_TX_DN(15)  OUT  = UPI_CPU1_CPU0_P1P1_DN<15>
  K21  UPI1_TX_DP(19)  OUT  = UPI_CPU1_CPU0_P1P1_DN<19>
  K23  DDR0_DQ(63)  BI  = M_G_DQ<63>
  K25  DDR0_DQ(56)  BI  = M_G_DQ<56>
  K27  VSS(1085)  GROUND  = GND
  K29  DDR0_DQ(54)  BI  = M_G_DQ<54>
  K31  DDR0_DQ(48)  BI  = M_G_DQ<48>
  K33  VSS(1084)  GROUND  = GND
  K35  DDR0_DQ(46)  BI  = M_G_DQ<46>
  K37  DDR0_DQ(40)  BI  = M_G_DQ<40>
  K39  VSS(1083)  GROUND  = GND
  K41  DDR1_DQ(38)  BI  = M_H_DQ<38>
  K43  DDR1_DQ(32)  BI  = M_H_DQ<32>
  K45  DDR0_CS_N(7)  OUT  = M_G_CS_N<7>
  K47  DDR0_MA(17)  OUT  = M_G_MA<17>
  K49  DDR0_MA(15)  OUT  = M_G_MA<15>
  K51  DDR1_CS_N(0)  OUT  = M_H_CS_N<0>
  K53  DDR1_PAR  OUT  = M_H_PAR
  K55  DDR1_BA(1)  OUT  = M_H_BA<1>
  K57  DDR1_MA(2)  OUT  = M_H_MA<2>
  K59  DDR1_MA(9)  OUT  = M_H_MA<9>
  K61  RSVD(267)  BI  = TP_CPU1_RSVD_267
  K63  DDR1_CKE(2)  OUT  = M_H_CKE<2>
  K65  VSS(1082)  GROUND  = GND
  K67  VSS(1081)  GROUND  = GND
  K69  VSS(1080)  GROUND  = GND
  K71  VSS(1079)  GROUND  = GND
  K73  VSS(1078)  GROUND  = GND
  K75  DDR0_DQS_DN(12)  BI  = M_G_DQS_DN<12>
  K77  VSS(1077)  GROUND  = GND
  K79  DDR1_DQS_DN(2)  BI  = M_H_DQS_DN<2>
  K81  VSS(1076)  GROUND  = GND
  K83  VSS(1075)  GROUND  = GND
  K85  VSS(1074)  GROUND  = GND
  L2  VSS(1072)  GROUND  = GND
  L4  UPI1_TX_DN(1)  OUT  = UPI_CPU1_CPU0_P1P1_DP<1>
  L6  VSS(1071)  GROUND  = GND
  L8  VSS(1226)  GROUND  = GND
  L10  VSS(1073)  GROUND  = GND
  L12  UPI1_RX_DN(7)  IN  = UPI_CPU0_CPU1_P1P1_DN<7>
  L14  VCCIO(57)  POWER  = PVCCIO_CPU1
  L16  VCCIO(56)  POWER  = PVCCIO_CPU1
  L18  UPI1_TX_DP(15)  OUT  = UPI_CPU1_CPU0_P1P1_DP<15>
  L20  VSS(1070)  GROUND  = GND
  L22  VSS(1069)  GROUND  = GND
  L24  DDR0_DQS_DP(16)  BI  = M_G_DQS_DP<16>
  L26  DDR0_DQ(60)  BI  = M_G_DQ<60>
  L28  DDR0_DQ(50)  BI  = M_G_DQ<50>
  L30  DDR0_DQS_DP(15)  BI  = M_G_DQS_DP<15>
  L32  DDR0_DQ(52)  BI  = M_G_DQ<52>
  L34  DDR0_DQ(42)  BI  = M_G_DQ<42>
  L36  DDR0_DQS_DP(14)  BI  = M_G_DQS_DP<14>
  L38  DDR0_DQ(44)  BI  = M_G_DQ<44>
  L40  DDR1_DQ(34)  BI  = M_H_DQ<34>
  L42  DDR1_DQS_DP(13)  BI  = M_H_DQS_DP<13>
  L46  VCCD012(13)  POWER  = PVDDQ_GHJ
  L48  VCCD012(14)  POWER  = PVDDQ_GHJ
  L50  VCCD012(15)  POWER  = PVDDQ_GHJ
  L52  VCCD012(16)  POWER  = PVDDQ_GHJ
  L54  VCCD012(17)  POWER  = PVDDQ_GHJ
  L56  VCCD012(18)  POWER  = PVDDQ_GHJ
  L58  VCCD012(19)  POWER  = PVDDQ_GHJ
  L60  VCCD012(20)  POWER  = PVDDQ_GHJ
  L62  VCCD012(21)  POWER  = PVDDQ_GHJ
  L64  DDR1_CKE(3)  OUT  = M_H_CKE<3>
  L66  DDR1_ECC(3)  BI  = M_H_ECC<3>
  L68  DDR1_DQS_DP(8)  BI  = M_H_DQS_DP<8>
  L70  DDR1_ECC(4)  BI  = M_H_ECC<4>
  L72  VSS(1068)  GROUND  = GND
  L74  DDR0_DQ(30)  BI  = M_G_DQ<30>
  L76  DDR0_DQ(24)  BI  = M_G_DQ<24>
  L78  VSS(1067)  GROUND  = GND
  L80  VSS(1066)  GROUND  = GND
  L82  VSS(1065)  GROUND  = GND
  L84  DDR0_DQ(11)  BI  = M_G_DQ<11>
  L86  DDR0_DQ(10)  BI  = M_G_DQ<10>
  M1  UPI0_TX_DP(0)  OUT  = UPI_CPU1_CPU0_P0P0_DN<0>
  M3  UPI1_TX_DN(0)  OUT  = UPI_CPU1_CPU0_P1P1_DP<0>
  M5  UPI1_TX_DP(2)  OUT  = UPI_CPU1_CPU0_P1P1_DP<2>
  M7  VCCIO(71)  POWER  = PVCCIO_CPU1
  M9  VCCIO(72)  POWER  = PVCCIO_CPU1
  M11  VCCIO(53)  POWER  = PVCCIO_CPU1
  M13  UPI1_RX_DP(8)  IN  = UPI_CPU0_CPU1_P1P1_DN<8>
  M15  VSS(1062)  GROUND  = GND
  M17  VSS(1061)  GROUND  = GND
  M19  VSS(1060)  GROUND  = GND
  M21  VCCIO(52)  POWER  = PVCCIO_CPU1
  M23  VSS(1059)  GROUND  = GND
  M25  VSS(1058)  GROUND  = GND
  M27  VSS(1057)  GROUND  = GND
  M29  VSS(1056)  GROUND  = GND
  M31  VSS(1055)  GROUND  = GND
  M33  VSS(1054)  GROUND  = GND
  M35  VSS(1053)  GROUND  = GND
  M37  VSS(1052)  GROUND  = GND
  M39  VSS(1051)  GROUND  = GND
  M41  VSS(1050)  GROUND  = GND
  M43  VSS(1049)  GROUND  = GND
  M45  DDR1_CS_N(6)  OUT  = M_H_CS_N<6>
  M47  DDR1_CID(2)  OUT  = M_H_C<2>
  M49  DDR1_ODT(2)  OUT  = M_H_ODT<2>
  M51  DDR1_MA(13)  OUT  = M_H_MA<13>
  M53  DDR1_CLK_DN(0)  OUT  = M_H_CLK_DN<0>
  M55  DDR1_MA(10)  OUT  = M_H_MA<10>
  M57  DDR1_CLK_DP(2)  OUT  = M_H_CLK_DP<2>
  M59  DDR1_MA(4)  OUT  = M_H_MA<4>
  M61  DDR1_BG(0)  OUT  = M_H_BG<0>
  M63  RSVD(266)  BI  = TP_CPU1_RSVD_266
  M65  VSS(1048)  GROUND  = GND
  M67  DDR1_ECC(7)  BI  = M_H_ECC<7>
  M69  DDR1_ECC(5)  BI  = M_H_ECC<5>
  M71  VSS(1047)  GROUND  = GND
  M73  DDR0_DQ(26)  BI  = M_G_DQ<26>
  M75  DDR0_DQS_DP(12)  BI  = M_G_DQS_DP<12>
  M77  DDR0_DQ(28)  BI  = M_G_DQ<28>
  M79  VSS(1046)  GROUND  = GND
  M81  DDR0_DQ(19)  BI  = M_G_DQ<19>
  M83  VSS(1045)  GROUND  = GND
  M85  VSS(1044)  GROUND  = GND
  N2  UPI0_TX_DN(0)  OUT  = UPI_CPU1_CPU0_P0P0_DP<0>
  N4  VSS(1033)  GROUND  = GND
  N6  VSS(1040)  GROUND  = GND
  N8  VSS(1032)  GROUND  = GND
  N10  UPI1_RX_DP(4)  IN  = UPI_CPU0_CPU1_P1P1_DP<4>
  N12  UPI1_RX_DP(7)  IN  = UPI_CPU0_CPU1_P1P1_DP<7>
  N14  UPI1_RX_DN(8)  IN  = UPI_CPU0_CPU1_P1P1_DP<8>
  N16  UPI1_RX_DP(11)  IN  = UPI_CPU0_CPU1_P1P1_DN<11>
  N18  VCCIO(73)  POWER  = PVCCIO_CPU1
  N20  VSS(1042)  GROUND  = GND
  N22  VSS(1041)  GROUND  = GND
  N24  DDR0_DQS_DN(7)  BI  = M_G_DQS_DN<7>
  N26  DDR0_DQ(61)  BI  = M_G_DQ<61>
  N28  DDR0_DQ(51)  BI  = M_G_DQ<51>
  N30  DDR0_DQS_DP(6)  BI  = M_G_DQS_DP<6>
  N32  DDR0_DQ(53)  BI  = M_G_DQ<53>
  N34  DDR0_DQ(43)  BI  = M_G_DQ<43>
  N36  DDR0_DQS_DP(5)  BI  = M_G_DQS_DP<5>
  N38  DDR0_DQ(45)  BI  = M_G_DQ<45>
  N40  DDR1_DQ(35)  BI  = M_H_DQ<35>
  N42  DDR1_DQS_DN(4)  BI  = M_H_DQS_DN<4>
  N46  DDR1_CS_N(2)  OUT  = M_H_CS_N<2>
  N48  DDR1_MA(17)  OUT  = M_H_MA<17>
  N50  DDR1_ODT(0)  OUT  = M_H_ODT<0>
  N52  DDR1_MA(15)  OUT  = M_H_MA<15>
  N54  DDR1_CLK_DP(0)  OUT  = M_H_CLK_DP<0>
  N56  DDR1_CLK_DN(2)  OUT  = M_H_CLK_DN<2>
  N58  DDR1_MA(3)  OUT  = M_H_MA<3>
  N60  DDR1_BG(1)  OUT  = M_H_BG<1>
  N62  DDR1_CKE(0)  OUT  = M_H_CKE<0>
  N64  VCCD012(22)  POWER  = PVDDQ_GHJ
  N66  VSS(1039)  GROUND  = GND
  N68  DDR1_DQS_DN(8)  BI  = M_H_DQS_DN<8>
  N70  VSS(1038)  GROUND  = GND
  N72  VSS(1037)  GROUND  = GND
  N74  VSS(1036)  GROUND  = GND
  N76  VSS(1035)  GROUND  = GND
  N78  VSS(1034)  GROUND  = GND
  N80  DDR0_DQ(23)  BI  = M_G_DQ<23>
  N82  DDR0_DQ(18)  BI  = M_G_DQ<18>
  N84  DDR0_DQ(15)  BI  = M_G_DQ<15>
  N86  DDR0_DQ(14)  BI  = M_G_DQ<14>
  P1  UPI0_TX_DN(1)  OUT  = UPI_CPU1_CPU0_P0P0_DP<1>
  P3  UPI1_TX_DP(0)  OUT  = UPI_CPU1_CPU0_P1P1_DN<0>
  P5  VCCIO(51)  POWER  = PVCCIO_CPU1
  P7  UPI1_RX_DN(1)  IN  = UPI_CPU0_CPU1_P1P1_DN<1>
  P9  UPI1_RX_DN(4)  IN  = UPI_CPU0_CPU1_P1P1_DN<4>
  P11  VSS(1031)  GROUND  = GND
  P13  UPI1_RX_DP(9)  IN  = UPI_CPU0_CPU1_P1P1_DP<9>
  P15  VSS(1030)  GROUND  = GND
  P17  UPI1_RX_DN(11)  IN  = UPI_CPU0_CPU1_P1P1_DP<11>
  P19  UPI1_RX_DP(14)  IN  = UPI_CPU0_CPU1_P1P1_DP<14>
  P21  UPI1_RX_DN(16)  IN  = UPI_CPU0_CPU1_P1P1_DN<16>
  P23  DDR0_DQ(58)  BI  = M_G_DQ<58>
  P25  DDR0_DQ(57)  BI  = M_G_DQ<57>
  P27  VSS(1029)  GROUND  = GND
  P29  DDR0_DQ(55)  BI  = M_G_DQ<55>
  P31  DDR0_DQ(49)  BI  = M_G_DQ<49>
  P33  VSS(1028)  GROUND  = GND
  P35  DDR0_DQ(47)  BI  = M_G_DQ<47>
  P37  DDR0_DQ(41)  BI  = M_G_DQ<41>
  P39  VSS(1027)  GROUND  = GND
  P41  DDR1_DQ(39)  BI  = M_H_DQ<39>
  P43  DDR1_DQ(36)  BI  = M_H_DQ<36>
  P45  VSS(429)  GROUND  = GND
  P47  VSS(453)  GROUND  = GND
  P49  VSS(454)  GROUND  = GND
  P51  VSS(476)  GROUND  = GND
  P53  VSS(483)  GROUND  = GND
  P55  VSS(545)  GROUND  = GND
  P57  VSS(567)  GROUND  = GND
  P59  VSS(578)  GROUND  = GND
  P61  VSS(594)  GROUND  = GND
